FILE_TYPE = MACRO_DRAWING;
SET COLOR_WIRE YELLOW;
SET COLOR_PROP ORANGE;
SET COLOR_DOT WHITE;
SET COLOR_ARC YELLOW;
SET COLOR_BODY GREEN;
SET COLOR_NOTE PURPLE;
SET PROP_DISPLAY VALUE;
SET PAGE_NUMBER P147;
FORCEADD QUANTA_TITLE_BLOCK_C..1
(0 0);
FORCEPROP 1 LAST CUSTOM_TXT_CDS <NAME_2>
J 0
(-3175 50);
FORCEPROP 1 LAST CUSTOM_TXT_CDS <NAME_1>
J 0
(-3175 175);
FORCEPROP 1 LAST CUSTOM_TXT_CDS <Q_NUMBER>
J 0
(-1403 103);
DISPLAY 1.212766 (-1403 103);
FORCEPROP 1 LAST CUSTOM_TXT_CDS <Q_PROJ>
J 0
(-2382 102);
DISPLAY 1.212766 (-2382 102);
FORCEPROP 1 LAST CUSTOM_TXT_CDS <Q_REV>
J 0
(-184 103);
DISPLAY 1.212766 (-184 103);
FORCEPROP 1 LAST CUSTOM_TXT_CDS <CON_LAST_MODIFIED>
J 0
(-1885 15);
DISPLAY 0.978723 (-1885 15);
FORCEPROP 1 LAST CUSTOM_TXT_CDS <CON_PAGE_NUM> OF <CON_TOTAL_PAGES>
J 0
(-446 18);
DISPLAY 0.978723 (-446 18);
FORCEPROP 1 LAST Q_DEPT BU9
J 1
(-3763 49);
DISPLAY 1.957447 (-3763 49);
PAINT GREEN (-3763 49);
FORCEPROP 1 LAST Q_TITLE Blank
J 0
(-9275 100);
DISPLAY 2.446809 (-9275 100);
PAINT GREEN (-9275 100);
FORCEPROP 0 LAST CDS_CON_LAST_MODIFIED Wed Jul 21 11:36:58 2021
J 0
(-1885 15);
DISPLAY INVISIBLE (-1885 15);
FORCEPROP 2 LAST PAGE_BORDER TRUE
J 0
(-7890 5250);
DISPLAY 0.638298 (-7890 5250);
PAINT PINK (-7890 5250);
DISPLAY INVISIBLE (-7890 5250);
FORCEPROP 1 LAST CDS_LMAN_SYM_OUTLINE -9475,6775,100,-125
J 0
(0 0);
DISPLAY 0.468085 (0 0);
PAINT GREEN (0 0);
DISPLAY INVISIBLE (0 0);
FORCEPROP 2 LAST CDS_LIB pure_quanta
J 0
(0 0);
DISPLAY INVISIBLE (0 0);
FORCEPROP 1 LAST COMMENT_BODY TRUE
J 0
(12 -13);
DISPLAY 0.978723 (12 -13);
PAINT GREEN (12 -13);
DISPLAY INVISIBLE (12 -13);
FORCEPROP 2 LAST CUSTOM_TXT_CDS <XR_PAGE_TITLE>
J 0
(-7890 5250);
DISPLAY 0.638298 (-7890 5250);
PAINT PINK (-7890 5250);
DISPLAY INVISIBLE (-7890 5250);
FORCEPROP 2 LAST CDS_XR_PAGE_TITLE CR-147 : @T6G_MB_LIB.T6G(SCH_1):PAGE147
J 0
(-7890 5250);
DISPLAY 0.638298 (-7890 5250);
PAINT PINK (-7890 5250);
DISPLAY INVISIBLE (-7890 5250);
QUIT
